(kicad_pcb
	(version 20260206)
	(generator "pcbnew")
	(generator_version "10.0")
	(general
		(thickness 1.6)
		(legacy_teardrops no)
	)
	(paper "A4")
	(title_block
		(title "03242023_DA0F0TMBIJ0_F0T_Motherboard_J_brd_V01_OCP.brd")
		(comment 1 "Grand Teton / footprints 1194-1197 of 6105")
	)
	(layers
		(0 "F.Cu" signal "TOP")
		(4 "In1.Cu" signal "GND")
		(6 "In2.Cu" signal "IN1")
		(8 "In3.Cu" signal "GND1")
		(10 "In4.Cu" signal "IN2")
		(12 "In5.Cu" signal "GND2")
		(14 "In6.Cu" signal "IN3")
		(16 "In7.Cu" signal "GND3")
		(18 "In8.Cu" signal "VCC")
		(20 "In9.Cu" signal "VCC1")
		(22 "In10.Cu" signal "GND4")
		(24 "In11.Cu" signal "IN4")
		(26 "In12.Cu" signal "GND5")
		(28 "In13.Cu" signal "IN5")
		(30 "In14.Cu" signal "GND6")
		(32 "In15.Cu" signal "IN6")
		(34 "In16.Cu" signal "GND7")
		(2 "B.Cu" signal "BOTTOM")
		(9 "F.Adhes" user "F.Adhesive")
		(11 "B.Adhes" user "B.Adhesive")
		(13 "F.Paste" user "Package Geometry/Pastemask Top")
		(15 "B.Paste" user "Package Geometry/Pastemask Bottom")
		(5 "F.SilkS" user "Ref Des/Silkscreen Top")
		(7 "B.SilkS" user "Ref Des/Silkscreen Bottom")
		(1 "F.Mask" user "Board Geometry/Soldermask Top")
		(3 "B.Mask" user "Board Geometry/Soldermask Bottom")
		(17 "Dwgs.User" user "User.Drawings")
		(19 "Cmts.User" user "User.Comments")
		(21 "Eco1.User" user "User.Eco1")
		(23 "Eco2.User" user "User.Eco2")
		(25 "Edge.Cuts" user "Board Geometry/Outline")
		(27 "Margin" user)
		(31 "F.CrtYd" user "Package Geometry/Place Bound Top")
		(29 "B.CrtYd" user "Package Geometry/Place Bound Bottom")
		(35 "F.Fab" user "Ref Des/Assembly Top")
		(33 "B.Fab" user "Ref Des/Assembly Bottom")
	)
	(footprint ""
		(layer "F.Cu")
		(at 378.099574 0.383794 180)
		(property "Reference" "J65"
			(at -4.451096 -1.394206 90)
			(unlocked yes)
			(layer "F.SilkS")
			(effects
				(font
					(size 0.7874 0.5842)
					(thickness 0.1524)
				)
				(justify left)
			)
		)
		(property "Value" ""
			(at 0 0 180)
			(layer "F.Fab")
			(effects
				(font
					(size 1.27 1.27)
				)
			)
		)
		(duplicate_pad_numbers_are_jumpers no)
		(fp_line
			(start 1.2192 2.1082)
			(end -1.2192 2.1082)
			(stroke
				(width 0.1524)
				(type default)
			)
			(layer "F.SilkS")
		)
		(fp_line
			(start 1.2192 -2.1082)
			(end 1.2192 2.1082)
			(stroke
				(width 0.1524)
				(type default)
			)
			(layer "F.SilkS")
		)
		(fp_line
			(start -1.2192 2.1082)
			(end -1.2192 -2.1082)
			(stroke
				(width 0.1524)
				(type default)
			)
			(layer "F.SilkS")
		)
		(fp_line
			(start -1.2192 -2.1082)
			(end 1.2192 -2.1082)
			(stroke
				(width 0.1524)
				(type default)
			)
			(layer "F.SilkS")
		)
		(pad "" np_thru_hole circle
			(at -2.8829 -1.27 90)
			(size 1.0414 1.0414)
			(drill 1.0414)
			(layers "*.Cu" "*.Mask")
			(clearance 0.381)
			(thermal_gap 0.381)
		)
		(pad "" np_thru_hole circle
			(at -2.8829 1.27 90)
			(size 1.0414 1.0414)
			(drill 1.0414)
			(layers "*.Cu" "*.Mask")
			(clearance 0.381)
			(thermal_gap 0.381)
		)
		(pad "" np_thru_hole circle
			(at 3.4671 -1.27 90)
			(size 1.0414 1.0414)
			(drill 1.0414)
			(layers "*.Cu" "*.Mask")
			(clearance 0.381)
			(thermal_gap 0.381)
		)
		(pad "" np_thru_hole circle
			(at 3.4671 1.27 90)
			(size 1.0414 1.0414)
			(drill 1.0414)
			(layers "*.Cu" "*.Mask")
			(clearance 0.381)
			(thermal_gap 0.381)
		)
		(pad "1" smd rect
			(at 0.8255 -0.249936 90)
			(size 0.3048 0.508)
			(layers "F.Cu" "F.Mask" "F.Paste")
			(net "DELTA_L_85_5INCH_IN1_DP")
		)
		(pad "2" smd rect
			(at 0.8255 0.249936 90)
			(size 0.3048 0.508)
			(layers "F.Cu" "F.Mask" "F.Paste")
			(net "DELTA_L_85_5INCH_IN1_DN")
		)
		(pad "3" smd circle
			(at 0 0 180)
			(size 0 0)
			(layers "F.Cu" "F.Mask" "F.Paste")
			(net "DELTA_L_GND_1")
		)
		(zone
			(layer "F.Cu")
			(hatch none 0.5)
			(connect_pads
				(clearance 0)
			)
			(min_thickness 0.25)
			(keepout
				(tracks not_allowed)
				(vias allowed)
				(pads allowed)
				(copperpour not_allowed)
				(footprints allowed)
			)
			(placement
				(enabled no)
				(sheetname "")
			)
			(fill
				(thermal_gap 0.5)
				(thermal_bridge_width 0.5)
				(island_removal_mode 0)
			)
			(polygon
				(pts
					(xy 376.981974 0.932434) (xy 376.981974 0.83693) (xy 377.578874 0.83693) (xy 377.578874 0.43053)
					(xy 376.981974 0.43053) (xy 376.981974 0.337058) (xy 377.578874 0.337058) (xy 377.578874 -0.069342)
					(xy 376.981974 -0.069342) (xy 376.981974 -0.164846) (xy 377.680474 -0.164846) (xy 377.680474 0.932434)
				)
			)
		)
		(zone
			(layers "F.Cu" "B.Cu" "In1.Cu" "In2.Cu" "In3.Cu" "In4.Cu" "In5.Cu" "In6.Cu"
				"In7.Cu" "In8.Cu" "In9.Cu" "In10.Cu" "In11.Cu" "In12.Cu" "In13.Cu" "In14.Cu"
				"In15.Cu" "In16.Cu"
			)
			(hatch none 0.5)
			(connect_pads
				(clearance 0)
			)
			(min_thickness 0.25)
			(keepout
				(tracks not_allowed)
				(vias allowed)
				(pads allowed)
				(copperpour not_allowed)
				(footprints allowed)
			)
			(placement
				(enabled no)
				(sheetname "")
			)
			(fill
				(thermal_gap 0.5)
				(thermal_bridge_width 0.5)
				(island_removal_mode 0)
			)
			(polygon
				(pts
					(arc
						(start 375.559574 -0.886206)
						(mid 373.705374 -0.886206)
						(end 375.559574 -0.886206)
					)
				)
			)
		)
		(zone
			(layers "F.Cu" "B.Cu" "In1.Cu" "In2.Cu" "In3.Cu" "In4.Cu" "In5.Cu" "In6.Cu"
				"In7.Cu" "In8.Cu" "In9.Cu" "In10.Cu" "In11.Cu" "In12.Cu" "In13.Cu" "In14.Cu"
				"In15.Cu" "In16.Cu"
			)
			(hatch none 0.5)
			(connect_pads
				(clearance 0)
			)
			(min_thickness 0.25)
			(keepout
				(tracks not_allowed)
				(vias allowed)
				(pads allowed)
				(copperpour not_allowed)
				(footprints allowed)
			)
			(placement
				(enabled no)
				(sheetname "")
			)
			(fill
				(thermal_gap 0.5)
				(thermal_bridge_width 0.5)
				(island_removal_mode 0)
			)
			(polygon
				(pts
					(arc
						(start 375.559574 1.653794)
						(mid 373.705374 1.653794)
						(end 375.559574 1.653794)
					)
				)
			)
		)
		(zone
			(layers "F.Cu" "B.Cu" "In1.Cu" "In2.Cu" "In3.Cu" "In4.Cu" "In5.Cu" "In6.Cu"
				"In7.Cu" "In8.Cu" "In9.Cu" "In10.Cu" "In11.Cu" "In12.Cu" "In13.Cu" "In14.Cu"
				"In15.Cu" "In16.Cu"
			)
			(hatch none 0.5)
			(connect_pads
				(clearance 0)
			)
			(min_thickness 0.25)
			(keepout
				(tracks not_allowed)
				(vias allowed)
				(pads allowed)
				(copperpour not_allowed)
				(footprints allowed)
			)
			(placement
				(enabled no)
				(sheetname "")
			)
			(fill
				(thermal_gap 0.5)
				(thermal_bridge_width 0.5)
				(island_removal_mode 0)
			)
			(polygon
				(pts
					(arc
						(start 381.909574 -0.886206)
						(mid 380.055374 -0.886206)
						(end 381.909574 -0.886206)
					)
				)
			)
		)
		(zone
			(layers "F.Cu" "B.Cu" "In1.Cu" "In2.Cu" "In3.Cu" "In4.Cu" "In5.Cu" "In6.Cu"
				"In7.Cu" "In8.Cu" "In9.Cu" "In10.Cu" "In11.Cu" "In12.Cu" "In13.Cu" "In14.Cu"
				"In15.Cu" "In16.Cu"
			)
			(hatch none 0.5)
			(connect_pads
				(clearance 0)
			)
			(min_thickness 0.25)
			(keepout
				(tracks not_allowed)
				(vias allowed)
				(pads allowed)
				(copperpour not_allowed)
				(footprints allowed)
			)
			(placement
				(enabled no)
				(sheetname "")
			)
			(fill
				(thermal_gap 0.5)
				(thermal_bridge_width 0.5)
				(island_removal_mode 0)
			)
			(polygon
				(pts
					(arc
						(start 381.909574 1.653794)
						(mid 380.055374 1.653794)
						(end 381.909574 1.653794)
					)
				)
			)
		)
	)
	(footprint ""
		(layer "F.Cu")
		(at 47.678594 -353.35718 -90)
		(property "Reference" "PC1243_P1_2"
			(at 0 0 270)
			(layer "F.SilkS")
			(hide yes)
			(effects
				(font
					(size 1.27 1.27)
				)
			)
		)
		(property "Value" ""
			(at 0 0 270)
			(layer "F.Fab")
			(effects
				(font
					(size 1.27 1.27)
				)
			)
		)
		(duplicate_pad_numbers_are_jumpers no)
		(fp_line
			(start -0.7874 0.4064)
			(end -0.7874 -0.4064)
			(stroke
				(width 0.1524)
				(type default)
			)
			(layer "F.SilkS")
		)
		(fp_line
			(start 0.7874 0.4064)
			(end -0.7874 0.4064)
			(stroke
				(width 0.1524)
				(type default)
			)
			(layer "F.SilkS")
		)
		(fp_line
			(start -0.7874 -0.4064)
			(end 0.7874 -0.4064)
			(stroke
				(width 0.1524)
				(type default)
			)
			(layer "F.SilkS")
		)
		(fp_line
			(start 0.7874 -0.4064)
			(end 0.7874 0.4064)
			(stroke
				(width 0.1524)
				(type default)
			)
			(layer "F.SilkS")
		)
		(fp_line
			(start -0.67945 0.3048)
			(end -0.67945 -0.305054)
			(stroke
				(width 0.1)
				(type default)
			)
			(layer "F.Fab")
		)
		(fp_line
			(start -0.12065 0.3048)
			(end -0.67945 0.3048)
			(stroke
				(width 0.1)
				(type default)
			)
			(layer "F.Fab")
		)
		(fp_line
			(start 0.120396 0.3048)
			(end 0.120396 0.2794)
			(stroke
				(width 0.1)
				(type default)
			)
			(layer "F.Fab")
		)
		(fp_line
			(start 0.67945 0.3048)
			(end 0.120396 0.3048)
			(stroke
				(width 0.1)
				(type default)
			)
			(layer "F.Fab")
		)
		(fp_line
			(start -0.12065 0.2794)
			(end -0.12065 0.3048)
			(stroke
				(width 0.1)
				(type default)
			)
			(layer "F.Fab")
		)
		(fp_line
			(start 0.120396 0.2794)
			(end -0.12065 0.2794)
			(stroke
				(width 0.1)
				(type default)
			)
			(layer "F.Fab")
		)
		(fp_line
			(start -0.12065 -0.2794)
			(end 0.12065 -0.2794)
			(stroke
				(width 0.1)
				(type default)
			)
			(layer "F.Fab")
		)
		(fp_line
			(start 0.12065 -0.2794)
			(end 0.12065 -0.3048)
			(stroke
				(width 0.1)
				(type default)
			)
			(layer "F.Fab")
		)
		(fp_line
			(start 0.12065 -0.3048)
			(end 0.67945 -0.3048)
			(stroke
				(width 0.1)
				(type default)
			)
			(layer "F.Fab")
		)
		(fp_line
			(start 0.67945 -0.3048)
			(end 0.67945 0.3048)
			(stroke
				(width 0.1)
				(type default)
			)
			(layer "F.Fab")
		)
		(fp_line
			(start -0.67945 -0.305054)
			(end -0.12065 -0.305054)
			(stroke
				(width 0.1)
				(type default)
			)
			(layer "F.Fab")
		)
		(fp_line
			(start -0.12065 -0.305054)
			(end -0.12065 -0.2794)
			(stroke
				(width 0.1)
				(type default)
			)
			(layer "F.Fab")
		)
		(pad "1" smd circle
			(at -0.40005 0 270)
			(size 0 0)
			(layers "F.Cu" "F.Mask" "F.Paste")
			(net "PVCCFA_EHV_FIVRA_CPU1_PVCC2")
		)
		(pad "2" smd circle
			(at 0.40005 0 270)
			(size 0 0)
			(layers "F.Cu" "F.Mask" "F.Paste")
			(net "GND")
		)
	)
	(footprint ""
		(layer "F.Cu")
		(at 115.06708 -106.238548 -90)
		(property "Reference" "R4044"
			(at 0 0 270)
			(layer "F.SilkS")
			(hide yes)
			(effects
				(font
					(size 1.27 1.27)
				)
			)
		)
		(property "Value" ""
			(at 0 0 270)
			(layer "F.Fab")
			(effects
				(font
					(size 1.27 1.27)
				)
			)
		)
		(duplicate_pad_numbers_are_jumpers no)
		(fp_line
			(start -0.7874 0.4064)
			(end -0.7874 -0.4064)
			(stroke
				(width 0.1524)
				(type default)
			)
			(layer "F.SilkS")
		)
		(fp_line
			(start 0.7874 0.4064)
			(end -0.7874 0.4064)
			(stroke
				(width 0.1524)
				(type default)
			)
			(layer "F.SilkS")
		)
		(fp_line
			(start -0.7874 -0.4064)
			(end 0.7874 -0.4064)
			(stroke
				(width 0.1524)
				(type default)
			)
			(layer "F.SilkS")
		)
		(fp_line
			(start 0.7874 -0.4064)
			(end 0.7874 0.4064)
			(stroke
				(width 0.1524)
				(type default)
			)
			(layer "F.SilkS")
		)
		(fp_line
			(start -0.67945 0.3048)
			(end -0.67945 -0.305054)
			(stroke
				(width 0.1)
				(type default)
			)
			(layer "F.Fab")
		)
		(fp_line
			(start -0.12065 0.3048)
			(end -0.67945 0.3048)
			(stroke
				(width 0.1)
				(type default)
			)
			(layer "F.Fab")
		)
		(fp_line
			(start 0.120396 0.3048)
			(end 0.120396 0.2794)
			(stroke
				(width 0.1)
				(type default)
			)
			(layer "F.Fab")
		)
		(fp_line
			(start 0.67945 0.3048)
			(end 0.120396 0.3048)
			(stroke
				(width 0.1)
				(type default)
			)
			(layer "F.Fab")
		)
		(fp_line
			(start -0.12065 0.2794)
			(end -0.12065 0.3048)
			(stroke
				(width 0.1)
				(type default)
			)
			(layer "F.Fab")
		)
		(fp_line
			(start 0.120396 0.2794)
			(end -0.12065 0.2794)
			(stroke
				(width 0.1)
				(type default)
			)
			(layer "F.Fab")
		)
		(fp_line
			(start -0.12065 -0.2794)
			(end 0.12065 -0.2794)
			(stroke
				(width 0.1)
				(type default)
			)
			(layer "F.Fab")
		)
		(fp_line
			(start 0.12065 -0.2794)
			(end 0.12065 -0.3048)
			(stroke
				(width 0.1)
				(type default)
			)
			(layer "F.Fab")
		)
		(fp_line
			(start 0.12065 -0.3048)
			(end 0.67945 -0.3048)
			(stroke
				(width 0.1)
				(type default)
			)
			(layer "F.Fab")
		)
		(fp_line
			(start 0.67945 -0.3048)
			(end 0.67945 0.3048)
			(stroke
				(width 0.1)
				(type default)
			)
			(layer "F.Fab")
		)
		(fp_line
			(start -0.67945 -0.305054)
			(end -0.12065 -0.305054)
			(stroke
				(width 0.1)
				(type default)
			)
			(layer "F.Fab")
		)
		(fp_line
			(start -0.12065 -0.305054)
			(end -0.12065 -0.2794)
			(stroke
				(width 0.1)
				(type default)
			)
			(layer "F.Fab")
		)
		(pad "1" smd circle
			(at -0.40005 0 270)
			(size 0 0)
			(layers "F.Cu" "F.Mask" "F.Paste")
			(net "RST_CPU0_DRAM_EF_PLD_LVT3_R_N")
		)
		(pad "2" smd circle
			(at 0.40005 0 270)
			(size 0 0)
			(layers "F.Cu" "F.Mask" "F.Paste")
			(net "RST_CPU0_DRAM_EF_PLD_LVT3_N")
		)
	)
	(footprint ""
		(layer "F.Cu")
		(at 446.03035 -374.891554)
		(property "Reference" "C1042"
			(at 0 0 0)
			(layer "F.SilkS")
			(hide yes)
			(effects
				(font
					(size 1.27 1.27)
				)
			)
		)
		(property "Value" ""
			(at 0 0 0)
			(layer "F.Fab")
			(effects
				(font
					(size 1.27 1.27)
				)
			)
		)
		(duplicate_pad_numbers_are_jumpers no)
		(fp_line
			(start -0.7874 -0.4064)
			(end 0.7874 -0.4064)
			(stroke
				(width 0.1524)
				(type default)
			)
			(layer "F.SilkS")
		)
		(fp_line
			(start -0.7874 0.4064)
			(end -0.7874 -0.4064)
			(stroke
				(width 0.1524)
				(type default)
			)
			(layer "F.SilkS")
		)
		(fp_line
			(start 0.7874 -0.4064)
			(end 0.7874 0.4064)
			(stroke
				(width 0.1524)
				(type default)
			)
			(layer "F.SilkS")
		)
		(fp_line
			(start 0.7874 0.4064)
			(end -0.7874 0.4064)
			(stroke
				(width 0.1524)
				(type default)
			)
			(layer "F.SilkS")
		)
		(fp_line
			(start -0.67945 -0.305054)
			(end -0.12065 -0.305054)
			(stroke
				(width 0.1)
				(type default)
			)
			(layer "F.Fab")
		)
		(fp_line
			(start -0.67945 0.3048)
			(end -0.67945 -0.305054)
			(stroke
				(width 0.1)
				(type default)
			)
			(layer "F.Fab")
		)
		(fp_line
			(start -0.12065 -0.305054)
			(end -0.12065 -0.2794)
			(stroke
				(width 0.1)
				(type default)
			)
			(layer "F.Fab")
		)
		(fp_line
			(start -0.12065 -0.2794)
			(end 0.12065 -0.2794)
			(stroke
				(width 0.1)
				(type default)
			)
			(layer "F.Fab")
		)
		(fp_line
			(start -0.12065 0.2794)
			(end -0.12065 0.3048)
			(stroke
				(width 0.1)
				(type default)
			)
			(layer "F.Fab")
		)
		(fp_line
			(start -0.12065 0.3048)
			(end -0.67945 0.3048)
			(stroke
				(width 0.1)
				(type default)
			)
			(layer "F.Fab")
		)
		(fp_line
			(start 0.120396 0.2794)
			(end -0.12065 0.2794)
			(stroke
				(width 0.1)
				(type default)
			)
			(layer "F.Fab")
		)
		(fp_line
			(start 0.120396 0.3048)
			(end 0.120396 0.2794)
			(stroke
				(width 0.1)
				(type default)
			)
			(layer "F.Fab")
		)
		(fp_line
			(start 0.12065 -0.3048)
			(end 0.67945 -0.3048)
			(stroke
				(width 0.1)
				(type default)
			)
			(layer "F.Fab")
		)
		(fp_line
			(start 0.12065 -0.2794)
			(end 0.12065 -0.3048)
			(stroke
				(width 0.1)
				(type default)
			)
			(layer "F.Fab")
		)
		(fp_line
			(start 0.67945 -0.3048)
			(end 0.67945 0.3048)
			(stroke
				(width 0.1)
				(type default)
			)
			(layer "F.Fab")
		)
		(fp_line
			(start 0.67945 0.3048)
			(end 0.120396 0.3048)
			(stroke
				(width 0.1)
				(type default)
			)
			(layer "F.Fab")
		)
		(pad "1" smd circle
			(at -0.40005 0)
			(size 0 0)
			(layers "F.Cu" "F.Mask" "F.Paste")
			(net "P5V_AUX")
		)
		(pad "2" smd circle
			(at 0.40005 0)
			(size 0 0)
			(layers "F.Cu" "F.Mask" "F.Paste")
			(net "GND")
		)
	)
)
